# S9S_MB_2U (Grand Teton) — schematic netlist excerpt (pin names and nets, part order shuffled) for the footprints in the layout excerpt that follows; sources: Cadence DE-HDL packaged netlist, KiCad conversion of 03242023_DA0F0TMBIJ0_F0T_Motherboard_J_brd_V01_OCP.brd

R17  Q_RES  200 1% CHIP  pkg 0402LF  page 14 : A = SVID_ALERT1_CPU0_N ; B = SVID_ALERT1_CPU0_R_N
C2019  Q_CAP  0.1UF 25V 10% X7R  pkg 0402  page 172 : A = P12V_SCM_R ; B = GND

(kicad_pcb
	(version 20260206)
	(generator "pcbnew")
	(generator_version "10.0")
	(general
		(thickness 1.6)
		(legacy_teardrops no)
	)
	(paper "A4")
	(title_block
		(title "03242023_DA0F0TMBIJ0_F0T_Motherboard_J_brd_V01_OCP.brd")
		(comment 1 "Grand Teton / footprints 5701-5702 of 6105")
	)
	(layers
		(0 "F.Cu" signal "TOP")
		(4 "In1.Cu" signal "GND")
		(6 "In2.Cu" signal "IN1")
		(8 "In3.Cu" signal "GND1")
		(10 "In4.Cu" signal "IN2")
		(12 "In5.Cu" signal "GND2")
		(14 "In6.Cu" signal "IN3")
		(16 "In7.Cu" signal "GND3")
		(18 "In8.Cu" signal "VCC")
		(20 "In9.Cu" signal "VCC1")
		(22 "In10.Cu" signal "GND4")
		(24 "In11.Cu" signal "IN4")
		(26 "In12.Cu" signal "GND5")
		(28 "In13.Cu" signal "IN5")
		(30 "In14.Cu" signal "GND6")
		(32 "In15.Cu" signal "IN6")
		(34 "In16.Cu" signal "GND7")
		(2 "B.Cu" signal "BOTTOM")
		(9 "F.Adhes" user "F.Adhesive")
		(11 "B.Adhes" user "B.Adhesive")
		(13 "F.Paste" user "Package Geometry/Pastemask Top")
		(15 "B.Paste" user "Package Geometry/Pastemask Bottom")
		(5 "F.SilkS" user "Ref Des/Silkscreen Top")
		(7 "B.SilkS" user "Ref Des/Silkscreen Bottom")
		(1 "F.Mask" user "Board Geometry/Soldermask Top")
		(3 "B.Mask" user "Board Geometry/Soldermask Bottom")
		(17 "Dwgs.User" user "User.Drawings")
		(19 "Cmts.User" user "User.Comments")
		(21 "Eco1.User" user "User.Eco1")
		(23 "Eco2.User" user "User.Eco2")
		(25 "Edge.Cuts" user "Board Geometry/Outline")
		(27 "Margin" user)
		(31 "F.CrtYd" user "Package Geometry/Place Bound Top")
		(29 "B.CrtYd" user "Package Geometry/Place Bound Bottom")
		(35 "F.Fab" user "Ref Des/Assembly Top")
		(33 "B.Fab" user "Ref Des/Assembly Bottom")
	)
	(footprint ""
		(layer "B.Cu")
		(at 208.56448 -35.804348 90)
		(property "Reference" "C2019"
			(at 0 0 90)
			(layer "B.SilkS")
			(hide yes)
			(effects
				(font
					(size 1.27 1.27)
				)
				(justify mirror)
			)
		)
		(property "Value" ""
			(at 0 0 90)
			(layer "B.Fab")
			(effects
				(font
					(size 1.27 1.27)
				)
				(justify mirror)
			)
		)
		(duplicate_pad_numbers_are_jumpers no)
		(fp_line
			(start 0.7874 -0.4064)
			(end -0.7874 -0.4064)
			(stroke
				(width 0.1524)
				(type default)
			)
			(layer "B.SilkS")
		)
		(fp_line
			(start -0.7874 -0.4064)
			(end -0.7874 0.4064)
			(stroke
				(width 0.1524)
				(type default)
			)
			(layer "B.SilkS")
		)
		(fp_line
			(start 0.7874 0.4064)
			(end 0.7874 -0.4064)
			(stroke
				(width 0.1524)
				(type default)
			)
			(layer "B.SilkS")
		)
		(fp_line
			(start -0.7874 0.4064)
			(end 0.7874 0.4064)
			(stroke
				(width 0.1524)
				(type default)
			)
			(layer "B.SilkS")
		)
		(fp_line
			(start 0.67945 -0.305054)
			(end 0.12065 -0.305054)
			(stroke
				(width 0.1)
				(type default)
			)
			(layer "B.Fab")
		)
		(fp_line
			(start 0.12065 -0.305054)
			(end 0.12065 -0.2794)
			(stroke
				(width 0.1)
				(type default)
			)
			(layer "B.Fab")
		)
		(fp_line
			(start -0.12065 -0.3048)
			(end -0.67945 -0.3048)
			(stroke
				(width 0.1)
				(type default)
			)
			(layer "B.Fab")
		)
		(fp_line
			(start -0.67945 -0.3048)
			(end -0.67945 0.3048)
			(stroke
				(width 0.1)
				(type default)
			)
			(layer "B.Fab")
		)
		(fp_line
			(start 0.12065 -0.2794)
			(end -0.12065 -0.2794)
			(stroke
				(width 0.1)
				(type default)
			)
			(layer "B.Fab")
		)
		(fp_line
			(start -0.12065 -0.2794)
			(end -0.12065 -0.3048)
			(stroke
				(width 0.1)
				(type default)
			)
			(layer "B.Fab")
		)
		(fp_line
			(start 0.12065 0.2794)
			(end 0.12065 0.3048)
			(stroke
				(width 0.1)
				(type default)
			)
			(layer "B.Fab")
		)
		(fp_line
			(start -0.120396 0.2794)
			(end 0.12065 0.2794)
			(stroke
				(width 0.1)
				(type default)
			)
			(layer "B.Fab")
		)
		(fp_line
			(start 0.67945 0.3048)
			(end 0.67945 -0.305054)
			(stroke
				(width 0.1)
				(type default)
			)
			(layer "B.Fab")
		)
		(fp_line
			(start 0.12065 0.3048)
			(end 0.67945 0.3048)
			(stroke
				(width 0.1)
				(type default)
			)
			(layer "B.Fab")
		)
		(fp_line
			(start -0.120396 0.3048)
			(end -0.120396 0.2794)
			(stroke
				(width 0.1)
				(type default)
			)
			(layer "B.Fab")
		)
		(fp_line
			(start -0.67945 0.3048)
			(end -0.120396 0.3048)
			(stroke
				(width 0.1)
				(type default)
			)
			(layer "B.Fab")
		)
		(pad "1" smd circle
			(at 0.40005 0 270)
			(size 0 0)
			(layers "B.Cu" "B.Mask" "B.Paste")
			(net "P12V_SCM_R")
		)
		(pad "2" smd circle
			(at -0.40005 0 270)
			(size 0 0)
			(layers "B.Cu" "B.Mask" "B.Paste")
			(net "GND")
		)
	)
	(footprint ""
		(layer "B.Cu")
		(at 308.085998 -192.60947 90)
		(property "Reference" "R17"
			(at 0 0 90)
			(layer "B.SilkS")
			(hide yes)
			(effects
				(font
					(size 1.27 1.27)
				)
				(justify mirror)
			)
		)
		(property "Value" ""
			(at 0 0 90)
			(layer "B.Fab")
			(effects
				(font
					(size 1.27 1.27)
				)
				(justify mirror)
			)
		)
		(duplicate_pad_numbers_are_jumpers no)
		(fp_line
			(start 0.7874 -0.4064)
			(end -0.7874 -0.4064)
			(stroke
				(width 0.1524)
				(type default)
			)
			(layer "B.SilkS")
		)
		(fp_line
			(start -0.7874 -0.4064)
			(end -0.7874 0.4064)
			(stroke
				(width 0.1524)
				(type default)
			)
			(layer "B.SilkS")
		)
		(fp_line
			(start 0.7874 0.4064)
			(end 0.7874 -0.4064)
			(stroke
				(width 0.1524)
				(type default)
			)
			(layer "B.SilkS")
		)
		(fp_line
			(start -0.7874 0.4064)
			(end 0.7874 0.4064)
			(stroke
				(width 0.1524)
				(type default)
			)
			(layer "B.SilkS")
		)
		(fp_line
			(start 0.67945 -0.305054)
			(end 0.12065 -0.305054)
			(stroke
				(width 0.1)
				(type default)
			)
			(layer "B.Fab")
		)
		(fp_line
			(start 0.12065 -0.305054)
			(end 0.12065 -0.2794)
			(stroke
				(width 0.1)
				(type default)
			)
			(layer "B.Fab")
		)
		(fp_line
			(start -0.12065 -0.3048)
			(end -0.67945 -0.3048)
			(stroke
				(width 0.1)
				(type default)
			)
			(layer "B.Fab")
		)
		(fp_line
			(start -0.67945 -0.3048)
			(end -0.67945 0.3048)
			(stroke
				(width 0.1)
				(type default)
			)
			(layer "B.Fab")
		)
		(fp_line
			(start 0.12065 -0.2794)
			(end -0.12065 -0.2794)
			(stroke
				(width 0.1)
				(type default)
			)
			(layer "B.Fab")
		)
		(fp_line
			(start -0.12065 -0.2794)
			(end -0.12065 -0.3048)
			(stroke
				(width 0.1)
				(type default)
			)
			(layer "B.Fab")
		)
		(fp_line
			(start 0.12065 0.2794)
			(end 0.12065 0.3048)
			(stroke
				(width 0.1)
				(type default)
			)
			(layer "B.Fab")
		)
		(fp_line
			(start -0.120396 0.2794)
			(end 0.12065 0.2794)
			(stroke
				(width 0.1)
				(type default)
			)
			(layer "B.Fab")
		)
		(fp_line
			(start 0.67945 0.3048)
			(end 0.67945 -0.305054)
			(stroke
				(width 0.1)
				(type default)
			)
			(layer "B.Fab")
		)
		(fp_line
			(start 0.12065 0.3048)
			(end 0.67945 0.3048)
			(stroke
				(width 0.1)
				(type default)
			)
			(layer "B.Fab")
		)
		(fp_line
			(start -0.120396 0.3048)
			(end -0.120396 0.2794)
			(stroke
				(width 0.1)
				(type default)
			)
			(layer "B.Fab")
		)
		(fp_line
			(start -0.67945 0.3048)
			(end -0.120396 0.3048)
			(stroke
				(width 0.1)
				(type default)
			)
			(layer "B.Fab")
		)
		(pad "1" smd circle
			(at 0.40005 0 270)
			(size 0 0)
			(layers "B.Cu" "B.Mask" "B.Paste")
			(net "SVID_ALERT1_CPU0_N")
		)
		(pad "2" smd circle
			(at -0.40005 0 270)
			(size 0 0)
			(layers "B.Cu" "B.Mask" "B.Paste")
			(net "SVID_ALERT1_CPU0_R_N")
		)
	)
)
